(kicad_pcb
	(version 20260206)
	(generator "pcbnew")
	(generator_version "10.0")
	(general
		(thickness 1.6)
		(legacy_teardrops no)
	)
	(paper "A4")
	(title_block
		(title "01162023_DA0F0TEBIF0_F0T_Expander_BD_F_brd_V02_OCP.brd")
		(comment 1 "Grand Teton / footprints 6691-6693 of 9728")
	)
	(layers
		(0 "F.Cu" signal "TOP")
		(4 "In1.Cu" signal "GND")
		(6 "In2.Cu" signal "VCC")
		(8 "In3.Cu" signal "VCC1")
		(10 "In4.Cu" signal "GND1")
		(12 "In5.Cu" signal "IN1")
		(14 "In6.Cu" signal "GND2")
		(16 "In7.Cu" signal "IN2")
		(18 "In8.Cu" signal "GND3")
		(20 "In9.Cu" signal "IN3")
		(22 "In10.Cu" signal "GND4")
		(24 "In11.Cu" signal "IN4")
		(26 "In12.Cu" signal "GND5")
		(28 "In13.Cu" signal "IN5")
		(30 "In14.Cu" signal "GND6")
		(32 "In15.Cu" signal "IN6")
		(34 "In16.Cu" signal "GND7")
		(2 "B.Cu" signal "BOTTOM")
		(9 "F.Adhes" user "F.Adhesive")
		(11 "B.Adhes" user "B.Adhesive")
		(13 "F.Paste" user "Package Geometry/Pastemask Top")
		(15 "B.Paste" user "Package Geometry/Pastemask Bottom")
		(5 "F.SilkS" user "Ref Des/Silkscreen Top")
		(7 "B.SilkS" user "Ref Des/Silkscreen Bottom")
		(1 "F.Mask" user "Board Geometry/Soldermask Top")
		(3 "B.Mask" user "Board Geometry/Soldermask Bottom")
		(17 "Dwgs.User" user "User.Drawings")
		(19 "Cmts.User" user "User.Comments")
		(21 "Eco1.User" user "User.Eco1")
		(23 "Eco2.User" user "User.Eco2")
		(25 "Edge.Cuts" user "Board Geometry/Outline")
		(27 "Margin" user)
		(31 "F.CrtYd" user "Package Geometry/Place Bound Top")
		(29 "B.CrtYd" user "Package Geometry/Place Bound Bottom")
		(35 "F.Fab" user "Ref Des/Assembly Top")
		(33 "B.Fab" user "Ref Des/Assembly Bottom")
	)
	(footprint ""
		(layer "F.Cu")
		(at 44.178728 -350.098614 90)
		(property "Reference" "C167"
			(at 0 0 90)
			(layer "F.SilkS")
			(hide yes)
			(effects
				(font
					(size 1.27 1.27)
				)
			)
		)
		(property "Value" ""
			(at 0 0 90)
			(layer "F.Fab")
			(effects
				(font
					(size 1.27 1.27)
				)
			)
		)
		(duplicate_pad_numbers_are_jumpers no)
		(fp_line
			(start 0.299974 -0.150114)
			(end 0.299974 0.150114)
			(stroke
				(width 0.1)
				(type default)
			)
			(layer "F.Fab")
		)
		(fp_line
			(start -0.299974 -0.150114)
			(end 0.299974 -0.150114)
			(stroke
				(width 0.1)
				(type default)
			)
			(layer "F.Fab")
		)
		(fp_line
			(start 0.299974 0.150114)
			(end -0.299974 0.150114)
			(stroke
				(width 0.1)
				(type default)
			)
			(layer "F.Fab")
		)
		(fp_line
			(start -0.299974 0.150114)
			(end -0.299974 -0.150114)
			(stroke
				(width 0.1)
				(type default)
			)
			(layer "F.Fab")
		)
		(pad "1" smd rect
			(at -0.2667 0 90)
			(size 0.3048 0.381)
			(layers "F.Cu" "F.Mask" "F.Paste")
			(net "P5E_PEX0_STN7_TX_DP<124>")
		)
		(pad "2" smd rect
			(at 0.2667 0 90)
			(size 0.3048 0.381)
			(layers "F.Cu" "F.Mask" "F.Paste")
			(net "P5E_PEX0_STN7_TX_C_DP<124>")
		)
	)
	(footprint ""
		(layer "F.Cu")
		(at 20.150074 -301.410116)
		(property "Reference" "H138"
			(at -0.365252 4.196842 0)
			(unlocked yes)
			(layer "F.SilkS")
			(effects
				(font
					(size 0.7874 0.5842)
					(thickness 0.1524)
				)
				(justify left)
			)
		)
		(property "Value" ""
			(at 0 0 0)
			(layer "F.Fab")
			(effects
				(font
					(size 1.27 1.27)
				)
			)
		)
		(duplicate_pad_numbers_are_jumpers no)
		(pad "1" thru_hole circle
			(at 0 0)
			(size 6.5024 6.5024)
			(drill 3.2004)
			(layers "*.Cu" "*.Mask")
			(remove_unused_layers no)
			(net "GND")
			(clearance -1.397)
		)
	)
	(footprint ""
		(layer "F.Cu")
		(at 36.638484 -109.20984)
		(property "Reference" "C54"
			(at 0 0 0)
			(layer "F.SilkS")
			(hide yes)
			(effects
				(font
					(size 1.27 1.27)
				)
			)
		)
		(property "Value" ""
			(at 0 0 0)
			(layer "F.Fab")
			(effects
				(font
					(size 1.27 1.27)
				)
			)
		)
		(duplicate_pad_numbers_are_jumpers no)
		(fp_line
			(start -0.299974 -0.150114)
			(end 0.299974 -0.150114)
			(stroke
				(width 0.1)
				(type default)
			)
			(layer "F.Fab")
		)
		(fp_line
			(start -0.299974 0.150114)
			(end -0.299974 -0.150114)
			(stroke
				(width 0.1)
				(type default)
			)
			(layer "F.Fab")
		)
		(fp_line
			(start 0.299974 -0.150114)
			(end 0.299974 0.150114)
			(stroke
				(width 0.1)
				(type default)
			)
			(layer "F.Fab")
		)
		(fp_line
			(start 0.299974 0.150114)
			(end -0.299974 0.150114)
			(stroke
				(width 0.1)
				(type default)
			)
			(layer "F.Fab")
		)
		(pad "1" smd rect
			(at -0.2667 0)
			(size 0.3048 0.381)
			(layers "F.Cu" "F.Mask" "F.Paste")
			(net "P5E_PEX0_STN1_TX_DP<21>")
		)
		(pad "2" smd rect
			(at 0.2667 0)
			(size 0.3048 0.381)
			(layers "F.Cu" "F.Mask" "F.Paste")
			(net "P5E_PEX0_STN1_TX_C_DP<21>")
		)
	)
)
